# BASEBOARD_FAB2 (Tioga Pass) — schematic netlist excerpt (pin names and nets, part order shuffled) for the footprints in the layout excerpt that follows; sources: Cadence DE-HDL packaged netlist, KiCad conversion of Wiwynn_Tioga_Pass_MB.brd

R7M9  RES  64.9 1.0% CHIP  pkg 0402  page 96 : A = PVDDQ_KLM ; B = PWRGD_CPU1_DRAMPWROK_KLM_G
C5T5  CAP_A  47UF 4V 20% X5R  pkg 0603V  page 217 : A = PVDDQ_ABC ; B = GND
C9B10  CAP_A  0.1UF 16V 10% X7R  pkg 0402V  page 186 : A = P5V_STBY ; B = GND

(kicad_pcb
	(version 20260206)
	(generator "pcbnew")
	(generator_version "10.0")
	(general
		(thickness 1.6)
		(legacy_teardrops no)
	)
	(paper "A4")
	(title_block
		(title "Wiwynn_Tioga_Pass_MB.brd")
		(comment 1 "Tioga Pass / footprints 3628-3630 of 4770")
	)
	(layers
		(0 "F.Cu" signal "TOP")
		(4 "In1.Cu" signal "L2GND")
		(6 "In2.Cu" signal "L3")
		(8 "In3.Cu" signal "L4GND")
		(10 "In4.Cu" signal "L5")
		(12 "In5.Cu" signal "L6GND")
		(14 "In6.Cu" signal "L7VCC")
		(16 "In7.Cu" signal "L8VCC")
		(18 "In8.Cu" signal "L9GND")
		(20 "In9.Cu" signal "L10")
		(22 "In10.Cu" signal "L11GND")
		(24 "In11.Cu" signal "L12")
		(26 "In12.Cu" signal "L13GND")
		(2 "B.Cu" signal "BOTTOM")
		(9 "F.Adhes" user "F.Adhesive")
		(11 "B.Adhes" user "B.Adhesive")
		(13 "F.Paste" user "Package Geometry/Pastemask Top")
		(15 "B.Paste" user "Package Geometry/Pastemask Bottom")
		(5 "F.SilkS" user "Ref Des/Silkscreen Top")
		(7 "B.SilkS" user "Ref Des/Silkscreen Bottom")
		(1 "F.Mask" user "Board Geometry/Soldermask Top")
		(3 "B.Mask" user "Board Geometry/Soldermask Bottom")
		(17 "Dwgs.User" user "User.Drawings")
		(19 "Cmts.User" user "User.Comments")
		(21 "Eco1.User" user "User.Eco1")
		(23 "Eco2.User" user "User.Eco2")
		(25 "Edge.Cuts" user "Board Geometry/Outline")
		(27 "Margin" user)
		(31 "F.CrtYd" user "Package Geometry/Place Bound Top")
		(29 "B.CrtYd" user "Package Geometry/Place Bound Bottom")
		(35 "F.Fab" user "Ref Des/Assembly Top")
		(33 "B.Fab" user "Ref Des/Assembly Bottom")
	)
	(footprint ""
		(layer "B.Cu")
		(at 156.414978 -119.384826 -90)
		(property "Reference" "R7M9"
			(at 0 0 90)
			(layer "B.SilkS")
			(hide yes)
			(effects
				(font
					(size 1.27 1.27)
				)
				(justify mirror)
			)
		)
		(property "Value" ""
			(at 0 0 90)
			(layer "B.Fab")
			(effects
				(font
					(size 1.27 1.27)
				)
				(justify mirror)
			)
		)
		(duplicate_pad_numbers_are_jumpers no)
		(fp_poly
			(pts
				(xy 0.2794 -0.1016) (xy -0.2794 -0.1016) (xy -0.2794 0.9906) (xy 0.2794 0.9906)
			)
			(stroke
				(width 0)
				(type default)
			)
			(fill no)
			(layer "B.CrtYd")
		)
		(fp_line
			(start -0.2794 0.9906)
			(end -0.2794 -0.1016)
			(stroke
				(width 0.1)
				(type default)
			)
			(layer "B.Fab")
		)
		(fp_line
			(start 0.2794 0.9906)
			(end -0.2794 0.9906)
			(stroke
				(width 0.1)
				(type default)
			)
			(layer "B.Fab")
		)
		(fp_line
			(start -0.2794 -0.1016)
			(end 0.2794 -0.1016)
			(stroke
				(width 0.1)
				(type default)
			)
			(layer "B.Fab")
		)
		(fp_line
			(start 0.2794 -0.1016)
			(end 0.2794 0.9906)
			(stroke
				(width 0.1)
				(type default)
			)
			(layer "B.Fab")
		)
		(pad "1" smd rect
			(at 0 0 90)
			(size 0.508 0.508)
			(layers "B.Cu" "B.Mask" "B.Paste")
			(net "PVDDQ_KLM")
		)
		(pad "2" smd rect
			(at 0 0.889 90)
			(size 0.508 0.508)
			(layers "B.Cu" "B.Mask" "B.Paste")
			(net "PWRGD_CPU1_DRAMPWROK_KLM_G")
		)
		(zone
			(layer "B.Cu")
			(hatch none 0.5)
			(connect_pads
				(clearance 0)
			)
			(min_thickness 0.25)
			(keepout
				(tracks not_allowed)
				(vias allowed)
				(pads allowed)
				(copperpour not_allowed)
				(footprints allowed)
			)
			(placement
				(enabled no)
				(sheetname "")
			)
			(fill
				(thermal_gap 0.5)
				(thermal_bridge_width 0.5)
				(island_removal_mode 0)
			)
			(polygon
				(pts
					(xy 155.779978 -119.130826) (xy 155.779978 -119.638826) (xy 156.160978 -119.638826) (xy 156.160978 -119.130826)
				)
			)
		)
		(zone
			(layer "B.Cu")
			(hatch none 0.5)
			(connect_pads
				(clearance 0)
			)
			(min_thickness 0.25)
			(keepout
				(tracks allowed)
				(vias not_allowed)
				(pads allowed)
				(copperpour not_allowed)
				(footprints allowed)
			)
			(placement
				(enabled no)
				(sheetname "")
			)
			(fill
				(thermal_gap 0.5)
				(thermal_bridge_width 0.5)
				(island_removal_mode 0)
			)
			(polygon
				(pts
					(xy 156.160978 -119.130826) (xy 156.160978 -119.638826) (xy 155.779978 -119.638826) (xy 155.779978 -119.130826)
				)
			)
		)
	)
	(footprint ""
		(layer "B.Cu")
		(at 276.000464 -17.7546 90)
		(property "Reference" "C5T5"
			(at -1.848866 0.752348 90)
			(unlocked yes)
			(layer "B.SilkS")
			(effects
				(font
					(size 1.27 0.9652)
					(thickness 0.1524)
				)
				(justify mirror)
			)
		)
		(property "Value" ""
			(at 0 0 90)
			(layer "B.Fab")
			(effects
				(font
					(size 1.27 1.27)
				)
				(justify mirror)
			)
		)
		(duplicate_pad_numbers_are_jumpers no)
		(fp_rect
			(start 0.500126 1.598422)
			(end -0.500126 -0.201422)
			(stroke
				(width 0)
				(type default)
			)
			(fill no)
			(layer "B.CrtYd")
		)
		(fp_line
			(start 0.500126 -0.201422)
			(end -0.500126 -0.201422)
			(stroke
				(width 0.1)
				(type default)
			)
			(layer "B.Fab")
		)
		(fp_line
			(start -0.500126 -0.201422)
			(end -0.500126 1.598422)
			(stroke
				(width 0.1)
				(type default)
			)
			(layer "B.Fab")
		)
		(fp_line
			(start 0.500126 1.598422)
			(end 0.500126 -0.201422)
			(stroke
				(width 0.1)
				(type default)
			)
			(layer "B.Fab")
		)
		(fp_line
			(start -0.500126 1.598422)
			(end 0.500126 1.598422)
			(stroke
				(width 0.1)
				(type default)
			)
			(layer "B.Fab")
		)
		(pad "1" smd rect
			(at 0 0)
			(size 0.889 0.9906)
			(layers "B.Cu" "B.Mask" "B.Paste")
			(net "PVDDQ_ABC")
		)
		(pad "2" smd rect
			(at 0 1.397)
			(size 0.889 0.9906)
			(layers "B.Cu" "B.Mask" "B.Paste")
			(net "GND")
		)
		(zone
			(layer "B.Cu")
			(hatch none 0.5)
			(connect_pads
				(clearance 0)
			)
			(min_thickness 0.25)
			(keepout
				(tracks not_allowed)
				(vias allowed)
				(pads allowed)
				(copperpour not_allowed)
				(footprints allowed)
			)
			(placement
				(enabled no)
				(sheetname "")
			)
			(fill
				(thermal_gap 0.5)
				(thermal_bridge_width 0.5)
				(island_removal_mode 0)
			)
			(polygon
				(pts
					(xy 276.952964 -18.2499) (xy 276.444964 -18.2499) (xy 276.444964 -17.2593) (xy 276.952964 -17.2593)
				)
			)
		)
		(zone
			(layer "B.Cu")
			(hatch none 0.5)
			(connect_pads
				(clearance 0)
			)
			(min_thickness 0.25)
			(keepout
				(tracks allowed)
				(vias not_allowed)
				(pads allowed)
				(copperpour not_allowed)
				(footprints allowed)
			)
			(placement
				(enabled no)
				(sheetname "")
			)
			(fill
				(thermal_gap 0.5)
				(thermal_bridge_width 0.5)
				(island_removal_mode 0)
			)
			(polygon
				(pts
					(xy 276.952964 -18.2499) (xy 276.444964 -18.2499) (xy 276.444964 -17.2593) (xy 276.952964 -17.2593)
				)
			)
		)
	)
	(footprint ""
		(layer "B.Cu")
		(at 484.850186 -121.325894 180)
		(property "Reference" "C9B10"
			(at 0.8382 -0.84963 180)
			(unlocked yes)
			(layer "B.SilkS")
			(effects
				(font
					(size 0.7874 0.5842)
					(thickness 0.1524)
				)
				(justify left mirror)
			)
		)
		(property "Value" ""
			(at 0 0 0)
			(layer "B.Fab")
			(effects
				(font
					(size 1.27 1.27)
				)
				(justify mirror)
			)
		)
		(duplicate_pad_numbers_are_jumpers no)
		(fp_poly
			(pts
				(xy -0.3048 -0.1016) (xy -0.3048 0.9906) (xy 0.3048 0.9906) (xy 0.3048 -0.1016)
			)
			(stroke
				(width 0)
				(type default)
			)
			(fill no)
			(layer "B.CrtYd")
		)
		(fp_line
			(start 0.3048 0.9906)
			(end -0.3048 0.9906)
			(stroke
				(width 0.1)
				(type default)
			)
			(layer "B.Fab")
		)
		(fp_line
			(start 0.3048 -0.1016)
			(end 0.3048 0.9906)
			(stroke
				(width 0.1)
				(type default)
			)
			(layer "B.Fab")
		)
		(fp_line
			(start -0.3048 0.9906)
			(end -0.3048 -0.1016)
			(stroke
				(width 0.1)
				(type default)
			)
			(layer "B.Fab")
		)
		(fp_line
			(start -0.3048 -0.1016)
			(end 0.3048 -0.1016)
			(stroke
				(width 0.1)
				(type default)
			)
			(layer "B.Fab")
		)
		(pad "1" smd rect
			(at 0 0)
			(size 0.508 0.508)
			(layers "B.Cu" "B.Mask" "B.Paste")
			(net "P5V_STBY")
		)
		(pad "2" smd rect
			(at 0 0.889)
			(size 0.508 0.508)
			(layers "B.Cu" "B.Mask" "B.Paste")
			(net "GND")
		)
		(zone
			(layer "B.Cu")
			(hatch none 0.5)
			(connect_pads
				(clearance 0)
			)
			(min_thickness 0.25)
			(keepout
				(tracks not_allowed)
				(vias allowed)
				(pads allowed)
				(copperpour not_allowed)
				(footprints allowed)
			)
			(placement
				(enabled no)
				(sheetname "")
			)
			(fill
				(thermal_gap 0.5)
				(thermal_bridge_width 0.5)
				(island_removal_mode 0)
			)
			(polygon
				(pts
					(xy 484.596186 -121.960894) (xy 485.104186 -121.960894) (xy 485.104186 -121.579894) (xy 484.596186 -121.579894)
				)
			)
		)
		(zone
			(layer "B.Cu")
			(hatch none 0.5)
			(connect_pads
				(clearance 0)
			)
			(min_thickness 0.25)
			(keepout
				(tracks allowed)
				(vias not_allowed)
				(pads allowed)
				(copperpour not_allowed)
				(footprints allowed)
			)
			(placement
				(enabled no)
				(sheetname "")
			)
			(fill
				(thermal_gap 0.5)
				(thermal_bridge_width 0.5)
				(island_removal_mode 0)
			)
			(polygon
				(pts
					(xy 484.596186 -121.579894) (xy 485.104186 -121.579894) (xy 485.104186 -121.960894) (xy 484.596186 -121.960894)
				)
			)
		)
	)
)
